FILE_TYPE = CONNECTIVITY;
{Allegro Design Entry HDL 17.2-2016 S081 (4005846) 1/11/2022}
"PAGE_NUMBER" = 212;
0"NC";
END.
